# BASEBOARD_FAB2 (Tioga Pass) — schematic netlist excerpt (pin names and nets, part order shuffled) for the footprints in the layout excerpt that follows; sources: Cadence DE-HDL packaged netlist, KiCad conversion of Wiwynn_Tioga_Pass_MB.brd

R4R5  RES  4.75K 1% CHIP  pkg 0402  page 21 : A = P3V3_STBY ; B = FM_CPU0_SKTOCC_LVT3_N
C5U5  CAP_A  47UF 4V 20% X5R  pkg 0603V  page 217 : A = PVDDQ_ABC ; B = GND
R9G30  RES  0.0 5% EMPTY  pkg 0402  page 152 : A = H_CPU0_MEMDEF_MEMHOT_LVT3_N ; B = H_CPU0_MEMDEF_MEMHOT_PCH_N

(kicad_pcb
	(version 20260206)
	(generator "pcbnew")
	(generator_version "10.0")
	(general
		(thickness 1.6)
		(legacy_teardrops no)
	)
	(paper "A4")
	(title_block
		(title "Wiwynn_Tioga_Pass_MB.brd")
		(comment 1 "Tioga Pass / footprints 2552-2554 of 4770")
	)
	(layers
		(0 "F.Cu" signal "TOP")
		(4 "In1.Cu" signal "L2GND")
		(6 "In2.Cu" signal "L3")
		(8 "In3.Cu" signal "L4GND")
		(10 "In4.Cu" signal "L5")
		(12 "In5.Cu" signal "L6GND")
		(14 "In6.Cu" signal "L7VCC")
		(16 "In7.Cu" signal "L8VCC")
		(18 "In8.Cu" signal "L9GND")
		(20 "In9.Cu" signal "L10")
		(22 "In10.Cu" signal "L11GND")
		(24 "In11.Cu" signal "L12")
		(26 "In12.Cu" signal "L13GND")
		(2 "B.Cu" signal "BOTTOM")
		(9 "F.Adhes" user "F.Adhesive")
		(11 "B.Adhes" user "B.Adhesive")
		(13 "F.Paste" user "Package Geometry/Pastemask Top")
		(15 "B.Paste" user "Package Geometry/Pastemask Bottom")
		(5 "F.SilkS" user "Ref Des/Silkscreen Top")
		(7 "B.SilkS" user "Ref Des/Silkscreen Bottom")
		(1 "F.Mask" user "Board Geometry/Soldermask Top")
		(3 "B.Mask" user "Board Geometry/Soldermask Bottom")
		(17 "Dwgs.User" user "User.Drawings")
		(19 "Cmts.User" user "User.Comments")
		(21 "Eco1.User" user "User.Eco1")
		(23 "Eco2.User" user "User.Eco2")
		(25 "Edge.Cuts" user "Board Geometry/Outline")
		(27 "Margin" user)
		(31 "F.CrtYd" user "Package Geometry/Place Bound Top")
		(29 "B.CrtYd" user "Package Geometry/Place Bound Bottom")
		(35 "F.Fab" user "Ref Des/Assembly Top")
		(33 "B.Fab" user "Ref Des/Assembly Bottom")
	)
	(footprint ""
		(layer "B.Cu")
		(at 266.397232 -8.1534 90)
		(property "Reference" "C5U5"
			(at -1.848866 0.752348 90)
			(unlocked yes)
			(layer "B.SilkS")
			(effects
				(font
					(size 1.27 0.9652)
					(thickness 0.1524)
				)
				(justify mirror)
			)
		)
		(property "Value" ""
			(at 0 0 90)
			(layer "B.Fab")
			(effects
				(font
					(size 1.27 1.27)
				)
				(justify mirror)
			)
		)
		(duplicate_pad_numbers_are_jumpers no)
		(fp_rect
			(start 0.500126 1.598422)
			(end -0.500126 -0.201422)
			(stroke
				(width 0)
				(type default)
			)
			(fill no)
			(layer "B.CrtYd")
		)
		(fp_line
			(start 0.500126 -0.201422)
			(end -0.500126 -0.201422)
			(stroke
				(width 0.1)
				(type default)
			)
			(layer "B.Fab")
		)
		(fp_line
			(start -0.500126 -0.201422)
			(end -0.500126 1.598422)
			(stroke
				(width 0.1)
				(type default)
			)
			(layer "B.Fab")
		)
		(fp_line
			(start 0.500126 1.598422)
			(end 0.500126 -0.201422)
			(stroke
				(width 0.1)
				(type default)
			)
			(layer "B.Fab")
		)
		(fp_line
			(start -0.500126 1.598422)
			(end 0.500126 1.598422)
			(stroke
				(width 0.1)
				(type default)
			)
			(layer "B.Fab")
		)
		(pad "1" smd rect
			(at 0 0)
			(size 0.889 0.9906)
			(layers "B.Cu" "B.Mask" "B.Paste")
			(net "PVDDQ_ABC")
		)
		(pad "2" smd rect
			(at 0 1.397)
			(size 0.889 0.9906)
			(layers "B.Cu" "B.Mask" "B.Paste")
			(net "GND")
		)
		(zone
			(layer "B.Cu")
			(hatch none 0.5)
			(connect_pads
				(clearance 0)
			)
			(min_thickness 0.25)
			(keepout
				(tracks allowed)
				(vias not_allowed)
				(pads allowed)
				(copperpour not_allowed)
				(footprints allowed)
			)
			(placement
				(enabled no)
				(sheetname "")
			)
			(fill
				(thermal_gap 0.5)
				(thermal_bridge_width 0.5)
				(island_removal_mode 0)
			)
			(polygon
				(pts
					(xy 267.349732 -8.6487) (xy 266.841732 -8.6487) (xy 266.841732 -7.6581) (xy 267.349732 -7.6581)
				)
			)
		)
		(zone
			(layer "B.Cu")
			(hatch none 0.5)
			(connect_pads
				(clearance 0)
			)
			(min_thickness 0.25)
			(keepout
				(tracks not_allowed)
				(vias allowed)
				(pads allowed)
				(copperpour not_allowed)
				(footprints allowed)
			)
			(placement
				(enabled no)
				(sheetname "")
			)
			(fill
				(thermal_gap 0.5)
				(thermal_bridge_width 0.5)
				(island_removal_mode 0)
			)
			(polygon
				(pts
					(xy 267.349732 -8.6487) (xy 266.841732 -8.6487) (xy 266.841732 -7.6581) (xy 267.349732 -7.6581)
				)
			)
		)
	)
	(footprint ""
		(layer "B.Cu")
		(at 327.95718 -58.724546 -90)
		(property "Reference" "R4R5"
			(at 0 0 90)
			(layer "B.SilkS")
			(hide yes)
			(effects
				(font
					(size 1.27 1.27)
				)
				(justify mirror)
			)
		)
		(property "Value" ""
			(at 0 0 90)
			(layer "B.Fab")
			(effects
				(font
					(size 1.27 1.27)
				)
				(justify mirror)
			)
		)
		(duplicate_pad_numbers_are_jumpers no)
		(fp_poly
			(pts
				(xy 0.2794 -0.1016) (xy -0.2794 -0.1016) (xy -0.2794 0.9906) (xy 0.2794 0.9906)
			)
			(stroke
				(width 0)
				(type default)
			)
			(fill no)
			(layer "B.CrtYd")
		)
		(fp_line
			(start -0.2794 0.9906)
			(end -0.2794 -0.1016)
			(stroke
				(width 0.1)
				(type default)
			)
			(layer "B.Fab")
		)
		(fp_line
			(start 0.2794 0.9906)
			(end -0.2794 0.9906)
			(stroke
				(width 0.1)
				(type default)
			)
			(layer "B.Fab")
		)
		(fp_line
			(start -0.2794 -0.1016)
			(end 0.2794 -0.1016)
			(stroke
				(width 0.1)
				(type default)
			)
			(layer "B.Fab")
		)
		(fp_line
			(start 0.2794 -0.1016)
			(end 0.2794 0.9906)
			(stroke
				(width 0.1)
				(type default)
			)
			(layer "B.Fab")
		)
		(pad "1" smd rect
			(at 0 0 90)
			(size 0.508 0.508)
			(layers "B.Cu" "B.Mask" "B.Paste")
			(net "P3V3_STBY")
		)
		(pad "2" smd rect
			(at 0 0.889 90)
			(size 0.508 0.508)
			(layers "B.Cu" "B.Mask" "B.Paste")
			(net "FM_CPU0_SKTOCC_LVT3_N")
		)
		(zone
			(layer "B.Cu")
			(hatch none 0.5)
			(connect_pads
				(clearance 0)
			)
			(min_thickness 0.25)
			(keepout
				(tracks not_allowed)
				(vias allowed)
				(pads allowed)
				(copperpour not_allowed)
				(footprints allowed)
			)
			(placement
				(enabled no)
				(sheetname "")
			)
			(fill
				(thermal_gap 0.5)
				(thermal_bridge_width 0.5)
				(island_removal_mode 0)
			)
			(polygon
				(pts
					(xy 327.32218 -58.470546) (xy 327.32218 -58.978546) (xy 327.70318 -58.978546) (xy 327.70318 -58.470546)
				)
			)
		)
		(zone
			(layer "B.Cu")
			(hatch none 0.5)
			(connect_pads
				(clearance 0)
			)
			(min_thickness 0.25)
			(keepout
				(tracks allowed)
				(vias not_allowed)
				(pads allowed)
				(copperpour not_allowed)
				(footprints allowed)
			)
			(placement
				(enabled no)
				(sheetname "")
			)
			(fill
				(thermal_gap 0.5)
				(thermal_bridge_width 0.5)
				(island_removal_mode 0)
			)
			(polygon
				(pts
					(xy 327.70318 -58.470546) (xy 327.70318 -58.978546) (xy 327.32218 -58.978546) (xy 327.32218 -58.470546)
				)
			)
		)
	)
	(footprint ""
		(layer "B.Cu")
		(at 425.5008 -15.0622 -90)
		(property "Reference" "R9G30"
			(at 0 0 90)
			(layer "B.SilkS")
			(hide yes)
			(effects
				(font
					(size 1.27 1.27)
				)
				(justify mirror)
			)
		)
		(property "Value" ""
			(at 0 0 90)
			(layer "B.Fab")
			(effects
				(font
					(size 1.27 1.27)
				)
				(justify mirror)
			)
		)
		(duplicate_pad_numbers_are_jumpers no)
		(fp_poly
			(pts
				(xy 0.2794 -0.1016) (xy -0.2794 -0.1016) (xy -0.2794 0.9906) (xy 0.2794 0.9906)
			)
			(stroke
				(width 0)
				(type default)
			)
			(fill no)
			(layer "B.CrtYd")
		)
		(fp_line
			(start -0.2794 0.9906)
			(end -0.2794 -0.1016)
			(stroke
				(width 0.1)
				(type default)
			)
			(layer "B.Fab")
		)
		(fp_line
			(start 0.2794 0.9906)
			(end -0.2794 0.9906)
			(stroke
				(width 0.1)
				(type default)
			)
			(layer "B.Fab")
		)
		(fp_line
			(start -0.2794 -0.1016)
			(end 0.2794 -0.1016)
			(stroke
				(width 0.1)
				(type default)
			)
			(layer "B.Fab")
		)
		(fp_line
			(start 0.2794 -0.1016)
			(end 0.2794 0.9906)
			(stroke
				(width 0.1)
				(type default)
			)
			(layer "B.Fab")
		)
		(pad "1" smd rect
			(at 0 0 90)
			(size 0.508 0.508)
			(layers "B.Cu" "B.Mask" "B.Paste")
			(net "H_CPU0_MEMDEF_MEMHOT_LVT3_N")
		)
		(pad "2" smd rect
			(at 0 0.889 90)
			(size 0.508 0.508)
			(layers "B.Cu" "B.Mask" "B.Paste")
			(net "H_CPU0_MEMDEF_MEMHOT_PCH_N")
		)
		(zone
			(layer "B.Cu")
			(hatch none 0.5)
			(connect_pads
				(clearance 0)
			)
			(min_thickness 0.25)
			(keepout
				(tracks not_allowed)
				(vias allowed)
				(pads allowed)
				(copperpour not_allowed)
				(footprints allowed)
			)
			(placement
				(enabled no)
				(sheetname "")
			)
			(fill
				(thermal_gap 0.5)
				(thermal_bridge_width 0.5)
				(island_removal_mode 0)
			)
			(polygon
				(pts
					(xy 424.8658 -14.8082) (xy 424.8658 -15.3162) (xy 425.2468 -15.3162) (xy 425.2468 -14.8082)
				)
			)
		)
		(zone
			(layer "B.Cu")
			(hatch none 0.5)
			(connect_pads
				(clearance 0)
			)
			(min_thickness 0.25)
			(keepout
				(tracks allowed)
				(vias not_allowed)
				(pads allowed)
				(copperpour not_allowed)
				(footprints allowed)
			)
			(placement
				(enabled no)
				(sheetname "")
			)
			(fill
				(thermal_gap 0.5)
				(thermal_bridge_width 0.5)
				(island_removal_mode 0)
			)
			(polygon
				(pts
					(xy 425.2468 -14.8082) (xy 425.2468 -15.3162) (xy 424.8658 -15.3162) (xy 424.8658 -14.8082)
				)
			)
		)
	)
)
